(kicad_pcb
	(version 20260206)
	(generator "pcbnew")
	(generator_version "10.0")
	(general
		(thickness 1.6)
		(legacy_teardrops no)
	)
	(paper "A4")
	(title_block
		(title "Bryce Canyon_IOM_M2_16342-2_OCP.brd")
		(comment 1 "Bryce Canyon / footprints 587-594 of 1146")
	)
	(layers
		(0 "F.Cu" signal "TOP")
		(4 "In1.Cu" signal "L2GND")
		(6 "In2.Cu" signal "L3")
		(8 "In3.Cu" signal "L4VCC")
		(10 "In4.Cu" signal "L5VCC")
		(12 "In5.Cu" signal "L6")
		(14 "In6.Cu" signal "L7GND")
		(2 "B.Cu" signal "BOTTOM")
		(9 "F.Adhes" user "F.Adhesive")
		(11 "B.Adhes" user "B.Adhesive")
		(13 "F.Paste" user "Package Geometry/Pastemask Top")
		(15 "B.Paste" user "Package Geometry/Pastemask Bottom")
		(5 "F.SilkS" user "Ref Des/Silkscreen Top")
		(7 "B.SilkS" user "Ref Des/Silkscreen Bottom")
		(1 "F.Mask" user "Board Geometry/Soldermask Top")
		(3 "B.Mask" user "Board Geometry/Soldermask Bottom")
		(17 "Dwgs.User" user "User.Drawings")
		(19 "Cmts.User" user "User.Comments")
		(21 "Eco1.User" user "User.Eco1")
		(23 "Eco2.User" user "User.Eco2")
		(25 "Edge.Cuts" user "Board Geometry/Outline")
		(27 "Margin" user)
		(31 "F.CrtYd" user "Package Geometry/Place Bound Top")
		(29 "B.CrtYd" user "Package Geometry/Place Bound Bottom")
		(35 "F.Fab" user "Ref Des/Assembly Top")
		(33 "B.Fab" user "Ref Des/Assembly Bottom")
	)
	(footprint ""
		(layer "F.Cu")
		(at 65.532 -166.497 180)
		(property "Reference" "C50"
			(at 0 0 180)
			(layer "F.SilkS")
			(hide yes)
			(effects
				(font
					(size 1.27 1.27)
				)
			)
		)
		(property "Value" "SCD1U16V2KX-3GP"
			(at 1.1811 -2.7051 180)
			(unlocked yes)
			(layer "F.Fab")
			(hide yes)
			(effects
				(font
					(size 1.016 1.016)
					(thickness 0.1524)
				)
			)
		)
		(property "Device Type" "C402H22"
			(at 1.1811 -4.2291 180)
			(unlocked yes)
			(layer "F.Fab")
			(hide yes)
			(effects
				(font
					(size 1.016 1.016)
					(thickness 0.1524)
				)
			)
		)
		(duplicate_pad_numbers_are_jumpers no)
		(fp_rect
			(start -0.4318 0.9525)
			(end 0.4318 -0.9525)
			(stroke
				(width 0)
				(type default)
			)
			(fill no)
			(layer "F.CrtYd")
		)
		(fp_rect
			(start -0.4318 0.9525)
			(end 0.4318 -0.9525)
			(stroke
				(width 0)
				(type default)
			)
			(fill no)
			(layer "F.Fab")
		)
		(pad "1" smd custom
			(at 0 -0.4445 180)
			(size 0.1524 0.1524)
			(layers "F.Cu" "F.Mask" "F.Paste")
			(net "FM_TPM_PRSNT_RST")
			(options
				(clearance outline)
				(anchor circle)
			)
			(primitives
				(gr_poly
					(pts
						(arc
							(start 0.3048 -0.2032)
							(mid 0.275042 -0.275042)
							(end 0.2032 -0.3048)
						)
						(arc
							(start -0.2032 -0.3048)
							(mid -0.275042 -0.275042)
							(end -0.3048 -0.2032)
						)
						(arc
							(start -0.3048 0.2032)
							(mid -0.275042 0.275042)
							(end -0.2032 0.3048)
						)
						(arc
							(start 0.2032 0.3048)
							(mid 0.275042 0.275042)
							(end 0.3048 0.2032)
						)
					)
					(width 0)
					(fill yes)
				)
			)
		)
		(pad "2" smd custom
			(at 0 0.4445 180)
			(size 0.1524 0.1524)
			(layers "F.Cu" "F.Mask" "F.Paste")
			(net "GND")
			(options
				(clearance outline)
				(anchor circle)
			)
			(primitives
				(gr_poly
					(pts
						(arc
							(start 0.3048 -0.2032)
							(mid 0.275042 -0.275042)
							(end 0.2032 -0.3048)
						)
						(arc
							(start -0.2032 -0.3048)
							(mid -0.275042 -0.275042)
							(end -0.3048 -0.2032)
						)
						(arc
							(start -0.3048 0.2032)
							(mid -0.275042 0.275042)
							(end -0.2032 0.3048)
						)
						(arc
							(start 0.2032 0.3048)
							(mid 0.275042 0.275042)
							(end 0.3048 0.2032)
						)
					)
					(width 0)
					(fill yes)
				)
			)
		)
	)
	(footprint ""
		(layer "F.Cu")
		(at 59.5376 -161.1122 90)
		(property "Reference" "R392"
			(at 0 0 90)
			(layer "F.SilkS")
			(hide yes)
			(effects
				(font
					(size 1.27 1.27)
				)
			)
		)
		(property "Value" "4K7R2F-GP"
			(at 0.064008 -3.993896 90)
			(unlocked yes)
			(layer "F.Fab")
			(hide yes)
			(effects
				(font
					(size 1.016 1.016)
					(thickness 0.1524)
				)
			)
		)
		(property "Device Type" "R402H16"
			(at 0.064008 -5.517896 90)
			(unlocked yes)
			(layer "F.Fab")
			(hide yes)
			(effects
				(font
					(size 1.016 1.016)
					(thickness 0.1524)
				)
			)
		)
		(duplicate_pad_numbers_are_jumpers no)
		(fp_line
			(start 0.508 -0.9398)
			(end -0.508 -0.9398)
			(stroke
				(width 0.1524)
				(type default)
			)
			(layer "F.SilkS")
		)
		(fp_line
			(start -0.508 -0.9398)
			(end -0.508 0.9398)
			(stroke
				(width 0.1524)
				(type default)
			)
			(layer "F.SilkS")
		)
		(fp_rect
			(start -0.508 0.9398)
			(end 0.508 -0.9398)
			(stroke
				(width 0)
				(type default)
			)
			(fill no)
			(layer "F.CrtYd")
		)
		(fp_rect
			(start -0.508 0.9398)
			(end 0.508 -0.9398)
			(stroke
				(width 0)
				(type default)
			)
			(fill no)
			(layer "F.Fab")
		)
		(pad "1" smd custom
			(at 0 -0.4445 90)
			(size 0.1397 0.1397)
			(layers "F.Cu" "F.Mask" "F.Paste")
			(net "P3V3_STBY")
			(options
				(clearance outline)
				(anchor circle)
			)
			(primitives
				(gr_poly
					(pts
						(arc
							(start -0.1778 -0.2794)
							(mid -0.249642 -0.249642)
							(end -0.2794 -0.1778)
						)
						(arc
							(start -0.2794 0.1778)
							(mid -0.249642 0.249642)
							(end -0.1778 0.2794)
						)
						(arc
							(start 0.1778 0.2794)
							(mid 0.249642 0.249642)
							(end 0.2794 0.1778)
						)
						(arc
							(start 0.2794 -0.1778)
							(mid 0.249642 -0.249642)
							(end 0.1778 -0.2794)
						)
					)
					(width 0)
					(fill yes)
				)
			)
		)
		(pad "2" smd custom
			(at 0 0.4445 90)
			(size 0.1397 0.1397)
			(layers "F.Cu" "F.Mask" "F.Paste")
			(net "MAC2_TXD1")
			(options
				(clearance outline)
				(anchor circle)
			)
			(primitives
				(gr_poly
					(pts
						(arc
							(start -0.1778 -0.2794)
							(mid -0.249642 -0.249642)
							(end -0.2794 -0.1778)
						)
						(arc
							(start -0.2794 0.1778)
							(mid -0.249642 0.249642)
							(end -0.1778 0.2794)
						)
						(arc
							(start 0.1778 0.2794)
							(mid 0.249642 0.249642)
							(end 0.2794 0.1778)
						)
						(arc
							(start 0.2794 -0.1778)
							(mid 0.249642 -0.249642)
							(end 0.1778 -0.2794)
						)
					)
					(width 0)
					(fill yes)
				)
			)
		)
	)
	(footprint ""
		(layer "F.Cu")
		(at 60.375546 -187.438538 -90)
		(property "Reference" "R479"
			(at 0 0 270)
			(layer "F.SilkS")
			(hide yes)
			(effects
				(font
					(size 1.27 1.27)
				)
			)
		)
		(property "Value" "0R6J-3-GP"
			(at -0.0508 -4.8514 270)
			(unlocked yes)
			(layer "F.Fab")
			(hide yes)
			(effects
				(font
					(size 1.016 1.016)
					(thickness 0.1524)
				)
			)
		)
		(property "Device Type" "R1206H28"
			(at 0 -6.3754 270)
			(unlocked yes)
			(layer "F.Fab")
			(hide yes)
			(effects
				(font
					(size 1.016 1.016)
					(thickness 0.1524)
				)
			)
		)
		(duplicate_pad_numbers_are_jumpers no)
		(fp_line
			(start -1.016 2.2352)
			(end -1.016 -2.2352)
			(stroke
				(width 0.1524)
				(type default)
			)
			(layer "F.SilkS")
		)
		(fp_line
			(start 1.016 2.2352)
			(end -1.016 2.2352)
			(stroke
				(width 0.1524)
				(type default)
			)
			(layer "F.SilkS")
		)
		(fp_line
			(start -1.016 -2.2352)
			(end 1.016 -2.2352)
			(stroke
				(width 0.1524)
				(type default)
			)
			(layer "F.SilkS")
		)
		(fp_line
			(start 1.016 -2.2352)
			(end 1.016 2.2352)
			(stroke
				(width 0.1524)
				(type default)
			)
			(layer "F.SilkS")
		)
		(fp_rect
			(start -1.0922 2.3114)
			(end 1.0922 -2.3114)
			(stroke
				(width 0)
				(type default)
			)
			(fill no)
			(layer "F.CrtYd")
		)
		(fp_poly
			(pts
				(xy -1.0922 -2.3114) (xy 1.0922 -2.3114) (xy 1.0922 2.3114) (xy -1.0922 2.3114)
			)
			(stroke
				(width 0)
				(type default)
			)
			(fill no)
			(layer "F.Fab")
		)
		(pad "1" smd rect
			(at 0 -1.397 270)
			(size 1.651 1.27)
			(layers "F.Cu" "F.Mask" "F.Paste")
			(net "P3V3_STBY")
		)
		(pad "2" smd rect
			(at 0 1.397 270)
			(size 1.651 1.27)
			(layers "F.Cu" "F.Mask" "F.Paste")
			(net "P3V3_STBY_OUT")
		)
	)
	(footprint ""
		(layer "F.Cu")
		(at 218.089988 -40.846756 180)
		(property "Reference" "R467"
			(at 0 0 180)
			(layer "F.SilkS")
			(hide yes)
			(effects
				(font
					(size 1.27 1.27)
				)
			)
		)
		(property "Value" "10KR2F-2-GP"
			(at 0.064008 -3.993896 180)
			(unlocked yes)
			(layer "F.Fab")
			(hide yes)
			(effects
				(font
					(size 1.016 1.016)
					(thickness 0.1524)
				)
			)
		)
		(property "Device Type" "R402H16"
			(at 0.064008 -5.517896 180)
			(unlocked yes)
			(layer "F.Fab")
			(hide yes)
			(effects
				(font
					(size 1.016 1.016)
					(thickness 0.1524)
				)
			)
		)
		(duplicate_pad_numbers_are_jumpers no)
		(fp_line
			(start 0.508 -0.9398)
			(end -0.508 -0.9398)
			(stroke
				(width 0.1524)
				(type default)
			)
			(layer "F.SilkS")
		)
		(fp_line
			(start -0.508 -0.9398)
			(end -0.508 0.9398)
			(stroke
				(width 0.1524)
				(type default)
			)
			(layer "F.SilkS")
		)
		(fp_rect
			(start -0.508 0.9398)
			(end 0.508 -0.9398)
			(stroke
				(width 0)
				(type default)
			)
			(fill no)
			(layer "F.CrtYd")
		)
		(fp_rect
			(start -0.508 0.9398)
			(end 0.508 -0.9398)
			(stroke
				(width 0)
				(type default)
			)
			(fill no)
			(layer "F.Fab")
		)
		(pad "1" smd custom
			(at 0 -0.4445 180)
			(size 0.1397 0.1397)
			(layers "F.Cu" "F.Mask" "F.Paste")
			(net "P5V_STBY_VREG")
			(options
				(clearance outline)
				(anchor circle)
			)
			(primitives
				(gr_poly
					(pts
						(arc
							(start -0.1778 -0.2794)
							(mid -0.249642 -0.249642)
							(end -0.2794 -0.1778)
						)
						(arc
							(start -0.2794 0.1778)
							(mid -0.249642 0.249642)
							(end -0.1778 0.2794)
						)
						(arc
							(start 0.1778 0.2794)
							(mid 0.249642 0.249642)
							(end 0.2794 0.1778)
						)
						(arc
							(start 0.2794 -0.1778)
							(mid 0.249642 -0.249642)
							(end 0.1778 -0.2794)
						)
					)
					(width 0)
					(fill yes)
				)
			)
		)
		(pad "2" smd custom
			(at 0 0.4445 180)
			(size 0.1397 0.1397)
			(layers "F.Cu" "F.Mask" "F.Paste")
			(net "PWRGD_P5V_STBY")
			(options
				(clearance outline)
				(anchor circle)
			)
			(primitives
				(gr_poly
					(pts
						(arc
							(start -0.1778 -0.2794)
							(mid -0.249642 -0.249642)
							(end -0.2794 -0.1778)
						)
						(arc
							(start -0.2794 0.1778)
							(mid -0.249642 0.249642)
							(end -0.1778 0.2794)
						)
						(arc
							(start 0.1778 0.2794)
							(mid 0.249642 0.249642)
							(end 0.2794 0.1778)
						)
						(arc
							(start 0.2794 -0.1778)
							(mid 0.249642 -0.249642)
							(end 0.1778 -0.2794)
						)
					)
					(width 0)
					(fill yes)
				)
			)
		)
	)
	(footprint ""
		(layer "F.Cu")
		(at 94.565216 -50.111914 -90)
		(property "Reference" "C186"
			(at 0 0 270)
			(layer "F.SilkS")
			(hide yes)
			(effects
				(font
					(size 1.27 1.27)
				)
			)
		)
		(property "Value" "SCD1U16V2KX-3GP"
			(at 1.1811 -2.7051 270)
			(unlocked yes)
			(layer "F.Fab")
			(hide yes)
			(effects
				(font
					(size 1.016 1.016)
					(thickness 0.1524)
				)
			)
		)
		(property "Device Type" "C402H22"
			(at 1.1811 -4.2291 270)
			(unlocked yes)
			(layer "F.Fab")
			(hide yes)
			(effects
				(font
					(size 1.016 1.016)
					(thickness 0.1524)
				)
			)
		)
		(duplicate_pad_numbers_are_jumpers no)
		(fp_rect
			(start -0.4318 0.9525)
			(end 0.4318 -0.9525)
			(stroke
				(width 0)
				(type default)
			)
			(fill no)
			(layer "F.CrtYd")
		)
		(fp_rect
			(start -0.4318 0.9525)
			(end 0.4318 -0.9525)
			(stroke
				(width 0)
				(type default)
			)
			(fill no)
			(layer "F.Fab")
		)
		(pad "1" smd custom
			(at 0 -0.4445 270)
			(size 0.1524 0.1524)
			(layers "F.Cu" "F.Mask" "F.Paste")
			(net "P3V3_STBY")
			(options
				(clearance outline)
				(anchor circle)
			)
			(primitives
				(gr_poly
					(pts
						(arc
							(start 0.3048 -0.2032)
							(mid 0.275042 -0.275042)
							(end 0.2032 -0.3048)
						)
						(arc
							(start -0.2032 -0.3048)
							(mid -0.275042 -0.275042)
							(end -0.3048 -0.2032)
						)
						(arc
							(start -0.3048 0.2032)
							(mid -0.275042 0.275042)
							(end -0.2032 0.3048)
						)
						(arc
							(start 0.2032 0.3048)
							(mid 0.275042 0.275042)
							(end 0.3048 0.2032)
						)
					)
					(width 0)
					(fill yes)
				)
			)
		)
		(pad "2" smd custom
			(at 0 0.4445 270)
			(size 0.1524 0.1524)
			(layers "F.Cu" "F.Mask" "F.Paste")
			(net "GND")
			(options
				(clearance outline)
				(anchor circle)
			)
			(primitives
				(gr_poly
					(pts
						(arc
							(start 0.3048 -0.2032)
							(mid 0.275042 -0.275042)
							(end 0.2032 -0.3048)
						)
						(arc
							(start -0.2032 -0.3048)
							(mid -0.275042 -0.275042)
							(end -0.3048 -0.2032)
						)
						(arc
							(start -0.3048 0.2032)
							(mid -0.275042 0.275042)
							(end -0.2032 0.3048)
						)
						(arc
							(start 0.2032 0.3048)
							(mid 0.275042 0.275042)
							(end 0.3048 0.2032)
						)
					)
					(width 0)
					(fill yes)
				)
			)
		)
	)
	(footprint ""
		(layer "F.Cu")
		(at 215.17864 -101.599492 90)
		(property "Reference" "R843"
			(at 0 0 90)
			(layer "F.SilkS")
			(hide yes)
			(effects
				(font
					(size 1.27 1.27)
				)
			)
		)
		(property "Value" "147KR2F-L-GP"
			(at 0.064008 -3.993896 90)
			(unlocked yes)
			(layer "F.Fab")
			(hide yes)
			(effects
				(font
					(size 1.016 1.016)
					(thickness 0.1524)
				)
			)
		)
		(property "Device Type" "R402H16"
			(at 0.064008 -5.517896 90)
			(unlocked yes)
			(layer "F.Fab")
			(hide yes)
			(effects
				(font
					(size 1.016 1.016)
					(thickness 0.1524)
				)
			)
		)
		(duplicate_pad_numbers_are_jumpers no)
		(fp_line
			(start 0.508 -0.9398)
			(end -0.508 -0.9398)
			(stroke
				(width 0.1524)
				(type default)
			)
			(layer "F.SilkS")
		)
		(fp_line
			(start -0.508 -0.9398)
			(end -0.508 0.9398)
			(stroke
				(width 0.1524)
				(type default)
			)
			(layer "F.SilkS")
		)
		(fp_rect
			(start -0.508 0.9398)
			(end 0.508 -0.9398)
			(stroke
				(width 0)
				(type default)
			)
			(fill no)
			(layer "F.CrtYd")
		)
		(fp_rect
			(start -0.508 0.9398)
			(end 0.508 -0.9398)
			(stroke
				(width 0)
				(type default)
			)
			(fill no)
			(layer "F.Fab")
		)
		(pad "1" smd custom
			(at 0 -0.4445 90)
			(size 0.1397 0.1397)
			(layers "F.Cu" "F.Mask" "F.Paste")
			(net "AGND_P3V3_M2")
			(options
				(clearance outline)
				(anchor circle)
			)
			(primitives
				(gr_poly
					(pts
						(arc
							(start -0.1778 -0.2794)
							(mid -0.249642 -0.249642)
							(end -0.2794 -0.1778)
						)
						(arc
							(start -0.2794 0.1778)
							(mid -0.249642 0.249642)
							(end -0.1778 0.2794)
						)
						(arc
							(start 0.1778 0.2794)
							(mid 0.249642 0.249642)
							(end 0.2794 0.1778)
						)
						(arc
							(start 0.2794 -0.1778)
							(mid 0.249642 -0.249642)
							(end 0.1778 -0.2794)
						)
					)
					(width 0)
					(fill yes)
				)
			)
		)
		(pad "2" smd custom
			(at 0 0.4445 90)
			(size 0.1397 0.1397)
			(layers "F.Cu" "F.Mask" "F.Paste")
			(net "P3V3_M2_TRIP")
			(options
				(clearance outline)
				(anchor circle)
			)
			(primitives
				(gr_poly
					(pts
						(arc
							(start -0.1778 -0.2794)
							(mid -0.249642 -0.249642)
							(end -0.2794 -0.1778)
						)
						(arc
							(start -0.2794 0.1778)
							(mid -0.249642 0.249642)
							(end -0.1778 0.2794)
						)
						(arc
							(start 0.1778 0.2794)
							(mid 0.249642 0.249642)
							(end 0.2794 0.1778)
						)
						(arc
							(start 0.2794 -0.1778)
							(mid 0.249642 -0.249642)
							(end 0.1778 -0.2794)
						)
					)
					(width 0)
					(fill yes)
				)
			)
		)
	)
	(footprint ""
		(layer "F.Cu")
		(at 47.01159 -158.5976)
		(property "Reference" "R171"
			(at 0 0 0)
			(layer "F.SilkS")
			(hide yes)
			(effects
				(font
					(size 1.27 1.27)
				)
			)
		)
		(property "Value" "0R2J-2-GP"
			(at 0.064008 -3.993896 0)
			(unlocked yes)
			(layer "F.Fab")
			(hide yes)
			(effects
				(font
					(size 1.016 1.016)
					(thickness 0.1524)
				)
			)
		)
		(property "Device Type" "R402H16"
			(at 0.064008 -5.517896 0)
			(unlocked yes)
			(layer "F.Fab")
			(hide yes)
			(effects
				(font
					(size 1.016 1.016)
					(thickness 0.1524)
				)
			)
		)
		(duplicate_pad_numbers_are_jumpers no)
		(fp_line
			(start -0.508 -0.9398)
			(end -0.508 0.9398)
			(stroke
				(width 0.1524)
				(type default)
			)
			(layer "F.SilkS")
		)
		(fp_line
			(start 0.508 -0.9398)
			(end -0.508 -0.9398)
			(stroke
				(width 0.1524)
				(type default)
			)
			(layer "F.SilkS")
		)
		(fp_rect
			(start -0.508 0.9398)
			(end 0.508 -0.9398)
			(stroke
				(width 0)
				(type default)
			)
			(fill no)
			(layer "F.CrtYd")
		)
		(fp_rect
			(start -0.508 0.9398)
			(end 0.508 -0.9398)
			(stroke
				(width 0)
				(type default)
			)
			(fill no)
			(layer "F.Fab")
		)
		(pad "1" smd custom
			(at 0 -0.4445)
			(size 0.1397 0.1397)
			(layers "F.Cu" "F.Mask" "F.Paste")
			(net "I2C_DPB_SCL_OUT")
			(options
				(clearance outline)
				(anchor circle)
			)
			(primitives
				(gr_poly
					(pts
						(arc
							(start -0.1778 -0.2794)
							(mid -0.249642 -0.249642)
							(end -0.2794 -0.1778)
						)
						(arc
							(start -0.2794 0.1778)
							(mid -0.249642 0.249642)
							(end -0.1778 0.2794)
						)
						(arc
							(start 0.1778 0.2794)
							(mid 0.249642 0.249642)
							(end 0.2794 0.1778)
						)
						(arc
							(start 0.2794 -0.1778)
							(mid 0.249642 -0.249642)
							(end 0.1778 -0.2794)
						)
					)
					(width 0)
					(fill yes)
				)
			)
		)
		(pad "2" smd custom
			(at 0 0.4445)
			(size 0.1397 0.1397)
			(layers "F.Cu" "F.Mask" "F.Paste")
			(net "BMC_SMB7_CLK")
			(options
				(clearance outline)
				(anchor circle)
			)
			(primitives
				(gr_poly
					(pts
						(arc
							(start -0.1778 -0.2794)
							(mid -0.249642 -0.249642)
							(end -0.2794 -0.1778)
						)
						(arc
							(start -0.2794 0.1778)
							(mid -0.249642 0.249642)
							(end -0.1778 0.2794)
						)
						(arc
							(start 0.1778 0.2794)
							(mid 0.249642 0.249642)
							(end 0.2794 0.1778)
						)
						(arc
							(start 0.2794 -0.1778)
							(mid 0.249642 -0.249642)
							(end 0.1778 -0.2794)
						)
					)
					(width 0)
					(fill yes)
				)
			)
		)
	)
	(footprint ""
		(layer "F.Cu")
		(at 81.70418 -178.529996 180)
		(property "Reference" "C192"
			(at 0 0 180)
			(layer "F.SilkS")
			(hide yes)
			(effects
				(font
					(size 1.27 1.27)
				)
			)
		)
		(property "Value" "SC10U6D3V5KX-4GP"
			(at -0.0762 -6.1214 180)
			(unlocked yes)
			(layer "F.Fab")
			(hide yes)
			(effects
				(font
					(size 1.016 1.016)
					(thickness 0.1524)
				)
			)
		)
		(property "Device Type" "C805H58"
			(at -0.0762 -8.1534 180)
			(unlocked yes)
			(layer "F.Fab")
			(hide yes)
			(effects
				(font
					(size 1.016 1.016)
					(thickness 0.1524)
				)
			)
		)
		(duplicate_pad_numbers_are_jumpers no)
		(fp_line
			(start 0.635 0)
			(end -0.635 0)
			(stroke
				(width 0.508)
				(type default)
			)
			(layer "F.SilkS")
		)
		(fp_rect
			(start -0.9652 1.778)
			(end 0.9652 -1.778)
			(stroke
				(width 0)
				(type default)
			)
			(fill no)
			(layer "F.CrtYd")
		)
		(fp_poly
			(pts
				(xy -0.9652 -1.778) (xy 0.9652 -1.778) (xy 0.9652 1.778) (xy -0.9652 1.778)
			)
			(stroke
				(width 0)
				(type default)
			)
			(fill no)
			(layer "F.Fab")
		)
		(pad "1" smd rect
			(at 0 -0.9652 180)
			(size 1.397 1.143)
			(layers "F.Cu" "F.Mask" "F.Paste")
			(net "TPS74801_P2V5_STBY_OUT")
		)
		(pad "2" smd rect
			(at 0 0.9652 180)
			(size 1.397 1.143)
			(layers "F.Cu" "F.Mask" "F.Paste")
			(net "GND")
		)
	)
)
